# BASEBOARD_FAB2 (Tioga Pass) — schematic netlist excerpt (pin names and nets, part order shuffled) for the footprints in the layout excerpt that follows; sources: Cadence DE-HDL packaged netlist, KiCad conversion of Wiwynn_Tioga_Pass_MB.brd

C4D34  CAP_A  22.0UF 4V 20% X6S  pkg 0603V  page 203 : A = PVCCIN_CPU0 ; B = GND
R6W47  RES  4.75K 1% EMPTY  pkg 0402  page 164 : A = PCA9554_A0 ; B = GND
R7A21  RES  68.1K 1% EMPTY  pkg 0402  page 219 : A = VR_PVDDQ_DEF_PH2_OCSET ; B = GND

(kicad_pcb
	(version 20260206)
	(generator "pcbnew")
	(generator_version "10.0")
	(general
		(thickness 1.6)
		(legacy_teardrops no)
	)
	(paper "A4")
	(title_block
		(title "Wiwynn_Tioga_Pass_MB.brd")
		(comment 1 "Tioga Pass / footprints 514-516 of 4770")
	)
	(layers
		(0 "F.Cu" signal "TOP")
		(4 "In1.Cu" signal "L2GND")
		(6 "In2.Cu" signal "L3")
		(8 "In3.Cu" signal "L4GND")
		(10 "In4.Cu" signal "L5")
		(12 "In5.Cu" signal "L6GND")
		(14 "In6.Cu" signal "L7VCC")
		(16 "In7.Cu" signal "L8VCC")
		(18 "In8.Cu" signal "L9GND")
		(20 "In9.Cu" signal "L10")
		(22 "In10.Cu" signal "L11GND")
		(24 "In11.Cu" signal "L12")
		(26 "In12.Cu" signal "L13GND")
		(2 "B.Cu" signal "BOTTOM")
		(9 "F.Adhes" user "F.Adhesive")
		(11 "B.Adhes" user "B.Adhesive")
		(13 "F.Paste" user "Package Geometry/Pastemask Top")
		(15 "B.Paste" user "Package Geometry/Pastemask Bottom")
		(5 "F.SilkS" user "Ref Des/Silkscreen Top")
		(7 "B.SilkS" user "Ref Des/Silkscreen Bottom")
		(1 "F.Mask" user "Board Geometry/Soldermask Top")
		(3 "B.Mask" user "Board Geometry/Soldermask Bottom")
		(17 "Dwgs.User" user "User.Drawings")
		(19 "Cmts.User" user "User.Comments")
		(21 "Eco1.User" user "User.Eco1")
		(23 "Eco2.User" user "User.Eco2")
		(25 "Edge.Cuts" user "Board Geometry/Outline")
		(27 "Margin" user)
		(31 "F.CrtYd" user "Package Geometry/Place Bound Top")
		(29 "B.CrtYd" user "Package Geometry/Place Bound Bottom")
		(35 "F.Fab" user "Ref Des/Assembly Top")
		(33 "B.Fab" user "Ref Des/Assembly Bottom")
	)
	(footprint ""
		(layer "F.Cu")
		(at 214.503 -70.358)
		(property "Reference" "C4D34"
			(at 0 0 0)
			(layer "F.SilkS")
			(hide yes)
			(effects
				(font
					(size 1.27 1.27)
				)
			)
		)
		(property "Value" ""
			(at 0 0 0)
			(layer "F.Fab")
			(effects
				(font
					(size 1.27 1.27)
				)
			)
		)
		(duplicate_pad_numbers_are_jumpers no)
		(fp_poly
			(pts
				(xy -0.4953 -0.2032) (xy 0.4953 -0.2032) (xy 0.4953 1.6002) (xy -0.4953 1.6002)
			)
			(stroke
				(width 0)
				(type default)
			)
			(fill no)
			(layer "F.CrtYd")
		)
		(fp_line
			(start -0.4953 -0.2032)
			(end 0.4953 -0.2032)
			(stroke
				(width 0.1)
				(type default)
			)
			(layer "F.Fab")
		)
		(fp_line
			(start -0.4953 1.6002)
			(end -0.4953 -0.2032)
			(stroke
				(width 0.1)
				(type default)
			)
			(layer "F.Fab")
		)
		(fp_line
			(start 0.4953 -0.2032)
			(end 0.4953 1.6002)
			(stroke
				(width 0.1)
				(type default)
			)
			(layer "F.Fab")
		)
		(fp_line
			(start 0.4953 1.6002)
			(end -0.4953 1.6002)
			(stroke
				(width 0.1)
				(type default)
			)
			(layer "F.Fab")
		)
		(pad "1" smd rect
			(at 0 0)
			(size 0.762 0.889)
			(layers "F.Cu" "F.Mask" "F.Paste")
			(net "PVCCIN_CPU0")
		)
		(pad "2" smd rect
			(at 0 1.397)
			(size 0.762 0.889)
			(layers "F.Cu" "F.Mask" "F.Paste")
			(net "GND")
		)
		(zone
			(layer "F.Cu")
			(hatch none 0.5)
			(connect_pads
				(clearance 0)
			)
			(min_thickness 0.25)
			(keepout
				(tracks not_allowed)
				(vias allowed)
				(pads allowed)
				(copperpour not_allowed)
				(footprints allowed)
			)
			(placement
				(enabled no)
				(sheetname "")
			)
			(fill
				(thermal_gap 0.5)
				(thermal_bridge_width 0.5)
				(island_removal_mode 0)
			)
			(polygon
				(pts
					(xy 214.122 -69.9135) (xy 214.884 -69.9135) (xy 214.884 -69.4055) (xy 214.122 -69.4055)
				)
			)
		)
	)
	(footprint ""
		(layer "F.Cu")
		(at 351.913444 -146.90471 90)
		(property "Reference" "R7A21"
			(at 0 0 90)
			(layer "F.SilkS")
			(hide yes)
			(effects
				(font
					(size 1.27 1.27)
				)
			)
		)
		(property "Value" ""
			(at 0 0 90)
			(layer "F.Fab")
			(effects
				(font
					(size 1.27 1.27)
				)
			)
		)
		(duplicate_pad_numbers_are_jumpers no)
		(fp_poly
			(pts
				(xy -0.2794 -0.1016) (xy 0.2794 -0.1016) (xy 0.2794 0.9906) (xy -0.2794 0.9906)
			)
			(stroke
				(width 0)
				(type default)
			)
			(fill no)
			(layer "F.CrtYd")
		)
		(fp_line
			(start 0.2794 -0.1016)
			(end -0.2794 -0.1016)
			(stroke
				(width 0.1)
				(type default)
			)
			(layer "F.Fab")
		)
		(fp_line
			(start -0.2794 -0.1016)
			(end -0.2794 0.9906)
			(stroke
				(width 0.1)
				(type default)
			)
			(layer "F.Fab")
		)
		(fp_line
			(start 0.2794 0.9906)
			(end 0.2794 -0.1016)
			(stroke
				(width 0.1)
				(type default)
			)
			(layer "F.Fab")
		)
		(fp_line
			(start -0.2794 0.9906)
			(end 0.2794 0.9906)
			(stroke
				(width 0.1)
				(type default)
			)
			(layer "F.Fab")
		)
		(pad "1" smd rect
			(at 0 0 90)
			(size 0.508 0.508)
			(layers "F.Cu" "F.Mask" "F.Paste")
			(net "VR_PVDDQ_DEF_PH2_OCSET")
		)
		(pad "2" smd rect
			(at 0 0.889 90)
			(size 0.508 0.508)
			(layers "F.Cu" "F.Mask" "F.Paste")
			(net "GND")
		)
		(zone
			(layer "F.Cu")
			(hatch none 0.5)
			(connect_pads
				(clearance 0)
			)
			(min_thickness 0.25)
			(keepout
				(tracks allowed)
				(vias not_allowed)
				(pads allowed)
				(copperpour not_allowed)
				(footprints allowed)
			)
			(placement
				(enabled no)
				(sheetname "")
			)
			(fill
				(thermal_gap 0.5)
				(thermal_bridge_width 0.5)
				(island_removal_mode 0)
			)
			(polygon
				(pts
					(xy 352.167444 -146.65071) (xy 352.167444 -147.15871) (xy 352.548444 -147.15871) (xy 352.548444 -146.65071)
				)
			)
		)
		(zone
			(layer "F.Cu")
			(hatch none 0.5)
			(connect_pads
				(clearance 0)
			)
			(min_thickness 0.25)
			(keepout
				(tracks not_allowed)
				(vias allowed)
				(pads allowed)
				(copperpour not_allowed)
				(footprints allowed)
			)
			(placement
				(enabled no)
				(sheetname "")
			)
			(fill
				(thermal_gap 0.5)
				(thermal_bridge_width 0.5)
				(island_removal_mode 0)
			)
			(polygon
				(pts
					(xy 352.548444 -146.65071) (xy 352.548444 -147.15871) (xy 352.167444 -147.15871) (xy 352.167444 -146.65071)
				)
			)
		)
	)
	(footprint ""
		(layer "F.Cu")
		(at 433.0446 -16.832072 180)
		(property "Reference" "R6W47"
			(at -0.8382 -0.67818 180)
			(unlocked yes)
			(layer "F.SilkS")
			(effects
				(font
					(size 0.4064 0.254)
					(thickness 0.1524)
				)
				(justify left)
			)
		)
		(property "Value" ""
			(at 0 0 180)
			(layer "F.Fab")
			(effects
				(font
					(size 1.27 1.27)
				)
			)
		)
		(duplicate_pad_numbers_are_jumpers no)
		(fp_poly
			(pts
				(xy -0.2794 -0.1016) (xy 0.2794 -0.1016) (xy 0.2794 0.9906) (xy -0.2794 0.9906)
			)
			(stroke
				(width 0)
				(type default)
			)
			(fill no)
			(layer "F.CrtYd")
		)
		(fp_line
			(start 0.2794 0.9906)
			(end 0.2794 -0.1016)
			(stroke
				(width 0.1)
				(type default)
			)
			(layer "F.Fab")
		)
		(fp_line
			(start 0.2794 -0.1016)
			(end -0.2794 -0.1016)
			(stroke
				(width 0.1)
				(type default)
			)
			(layer "F.Fab")
		)
		(fp_line
			(start -0.2794 0.9906)
			(end 0.2794 0.9906)
			(stroke
				(width 0.1)
				(type default)
			)
			(layer "F.Fab")
		)
		(fp_line
			(start -0.2794 -0.1016)
			(end -0.2794 0.9906)
			(stroke
				(width 0.1)
				(type default)
			)
			(layer "F.Fab")
		)
		(pad "1" smd rect
			(at 0 0 180)
			(size 0.508 0.508)
			(layers "F.Cu" "F.Mask" "F.Paste")
			(net "PCA9554_A0")
		)
		(pad "2" smd rect
			(at 0 0.889 180)
			(size 0.508 0.508)
			(layers "F.Cu" "F.Mask" "F.Paste")
			(net "GND")
		)
		(zone
			(layer "F.Cu")
			(hatch none 0.5)
			(connect_pads
				(clearance 0)
			)
			(min_thickness 0.25)
			(keepout
				(tracks not_allowed)
				(vias allowed)
				(pads allowed)
				(copperpour not_allowed)
				(footprints allowed)
			)
			(placement
				(enabled no)
				(sheetname "")
			)
			(fill
				(thermal_gap 0.5)
				(thermal_bridge_width 0.5)
				(island_removal_mode 0)
			)
			(polygon
				(pts
					(xy 433.2986 -17.467072) (xy 432.7906 -17.467072) (xy 432.7906 -17.086072) (xy 433.2986 -17.086072)
				)
			)
		)
		(zone
			(layer "F.Cu")
			(hatch none 0.5)
			(connect_pads
				(clearance 0)
			)
			(min_thickness 0.25)
			(keepout
				(tracks allowed)
				(vias not_allowed)
				(pads allowed)
				(copperpour not_allowed)
				(footprints allowed)
			)
			(placement
				(enabled no)
				(sheetname "")
			)
			(fill
				(thermal_gap 0.5)
				(thermal_bridge_width 0.5)
				(island_removal_mode 0)
			)
			(polygon
				(pts
					(xy 433.2986 -17.086072) (xy 432.7906 -17.086072) (xy 432.7906 -17.467072) (xy 433.2986 -17.467072)
				)
			)
		)
	)
)
